# T6G (Grand Teton) — schematic netlist excerpt (pin names and nets, part order shuffled) for the footprints in the layout excerpt that follows; sources: Cadence DE-HDL packaged netlist, KiCad conversion of 04192023_DAF0TMB3IC0_F0TG_MB_C_brd_V02_OCP.brd

C2115  Q_CAP  22UF 4V 20% X6S  pkg C0402  page 74 : A = PVDD11_S3_P1 ; B = GND
C494  Q_CAP  4.7UF 6.3V 20% X6S  pkg 0402  page 356 : A = P0V9_CPU1_RT3_2A ; B = GND

(kicad_pcb
	(version 20260206)
	(generator "pcbnew")
	(generator_version "10.0")
	(general
		(thickness 1.6)
		(legacy_teardrops no)
	)
	(paper "A4")
	(title_block
		(title "04192023_DAF0TMB3IC0_F0TG_MB_C_brd_V02_OCP.brd")
		(comment 1 "Grand Teton / footprints 5351-5352 of 8354")
	)
	(layers
		(0 "F.Cu" signal "TOP")
		(4 "In1.Cu" signal "GND")
		(6 "In2.Cu" signal "IN1")
		(8 "In3.Cu" signal "GND1")
		(10 "In4.Cu" signal "IN2")
		(12 "In5.Cu" signal "GND2")
		(14 "In6.Cu" signal "IN3")
		(16 "In7.Cu" signal "GND3")
		(18 "In8.Cu" signal "VCC")
		(20 "In9.Cu" signal "VCC1")
		(22 "In10.Cu" signal "GND4")
		(24 "In11.Cu" signal "IN4")
		(26 "In12.Cu" signal "GND5")
		(28 "In13.Cu" signal "IN5")
		(30 "In14.Cu" signal "GND6")
		(32 "In15.Cu" signal "IN6")
		(34 "In16.Cu" signal "GND7")
		(2 "B.Cu" signal "BOTTOM")
		(9 "F.Adhes" user "F.Adhesive")
		(11 "B.Adhes" user "B.Adhesive")
		(13 "F.Paste" user "Package Geometry/Pastemask Top")
		(15 "B.Paste" user "Package Geometry/Pastemask Bottom")
		(5 "F.SilkS" user "Ref Des/Silkscreen Top")
		(7 "B.SilkS" user "Ref Des/Silkscreen Bottom")
		(1 "F.Mask" user "Board Geometry/Soldermask Top")
		(3 "B.Mask" user "Board Geometry/Soldermask Bottom")
		(17 "Dwgs.User" user "User.Drawings")
		(19 "Cmts.User" user "User.Comments")
		(21 "Eco1.User" user "User.Eco1")
		(23 "Eco2.User" user "User.Eco2")
		(25 "Edge.Cuts" user "Board Geometry/Outline")
		(27 "Margin" user)
		(31 "F.CrtYd" user "Package Geometry/Place Bound Top")
		(29 "B.CrtYd" user "Package Geometry/Place Bound Bottom")
		(35 "F.Fab" user "Ref Des/Assembly Top")
		(33 "B.Fab" user "Ref Des/Assembly Bottom")
	)
	(footprint ""
		(layer "B.Cu")
		(at 102.783386 -266.005564)
		(property "Reference" "C2115"
			(at 0 0 0)
			(layer "B.SilkS")
			(hide yes)
			(effects
				(font
					(size 1.27 1.27)
				)
				(justify mirror)
			)
		)
		(property "Value" ""
			(at 0 0 0)
			(layer "B.Fab")
			(effects
				(font
					(size 1.27 1.27)
				)
				(justify mirror)
			)
		)
		(duplicate_pad_numbers_are_jumpers no)
		(fp_line
			(start -0.7874 -0.4064)
			(end -0.7874 0.4064)
			(stroke
				(width 0.1524)
				(type default)
			)
			(layer "B.SilkS")
		)
		(fp_line
			(start -0.7874 0.4064)
			(end 0.7874 0.4064)
			(stroke
				(width 0.1524)
				(type default)
			)
			(layer "B.SilkS")
		)
		(fp_line
			(start 0.7874 -0.4064)
			(end -0.7874 -0.4064)
			(stroke
				(width 0.1524)
				(type default)
			)
			(layer "B.SilkS")
		)
		(fp_line
			(start 0.7874 0.4064)
			(end 0.7874 -0.4064)
			(stroke
				(width 0.1524)
				(type default)
			)
			(layer "B.SilkS")
		)
		(fp_line
			(start -0.67945 -0.3048)
			(end -0.67945 0.3048)
			(stroke
				(width 0.1)
				(type default)
			)
			(layer "B.Fab")
		)
		(fp_line
			(start -0.67945 0.3048)
			(end -0.120396 0.3048)
			(stroke
				(width 0.1)
				(type default)
			)
			(layer "B.Fab")
		)
		(fp_line
			(start -0.12065 -0.3048)
			(end -0.67945 -0.3048)
			(stroke
				(width 0.1)
				(type default)
			)
			(layer "B.Fab")
		)
		(fp_line
			(start -0.12065 -0.2794)
			(end -0.12065 -0.3048)
			(stroke
				(width 0.1)
				(type default)
			)
			(layer "B.Fab")
		)
		(fp_line
			(start -0.120396 0.2794)
			(end 0.12065 0.2794)
			(stroke
				(width 0.1)
				(type default)
			)
			(layer "B.Fab")
		)
		(fp_line
			(start -0.120396 0.3048)
			(end -0.120396 0.2794)
			(stroke
				(width 0.1)
				(type default)
			)
			(layer "B.Fab")
		)
		(fp_line
			(start 0.12065 -0.305054)
			(end 0.12065 -0.2794)
			(stroke
				(width 0.1)
				(type default)
			)
			(layer "B.Fab")
		)
		(fp_line
			(start 0.12065 -0.2794)
			(end -0.12065 -0.2794)
			(stroke
				(width 0.1)
				(type default)
			)
			(layer "B.Fab")
		)
		(fp_line
			(start 0.12065 0.2794)
			(end 0.12065 0.3048)
			(stroke
				(width 0.1)
				(type default)
			)
			(layer "B.Fab")
		)
		(fp_line
			(start 0.12065 0.3048)
			(end 0.67945 0.3048)
			(stroke
				(width 0.1)
				(type default)
			)
			(layer "B.Fab")
		)
		(fp_line
			(start 0.67945 -0.305054)
			(end 0.12065 -0.305054)
			(stroke
				(width 0.1)
				(type default)
			)
			(layer "B.Fab")
		)
		(fp_line
			(start 0.67945 0.3048)
			(end 0.67945 -0.305054)
			(stroke
				(width 0.1)
				(type default)
			)
			(layer "B.Fab")
		)
		(pad "1" smd circle
			(at 0.40005 0 180)
			(size 0 0)
			(layers "B.Cu" "B.Mask" "B.Paste")
			(net "PVDD11_S3_P1")
		)
		(pad "2" smd circle
			(at -0.40005 0 180)
			(size 0 0)
			(layers "B.Cu" "B.Mask" "B.Paste")
			(net "GND")
		)
	)
	(footprint ""
		(layer "B.Cu")
		(at 131.29133 -390.560052 90)
		(property "Reference" "C494"
			(at 0 0 90)
			(layer "B.SilkS")
			(hide yes)
			(effects
				(font
					(size 1.27 1.27)
				)
				(justify mirror)
			)
		)
		(property "Value" ""
			(at 0 0 90)
			(layer "B.Fab")
			(effects
				(font
					(size 1.27 1.27)
				)
				(justify mirror)
			)
		)
		(duplicate_pad_numbers_are_jumpers no)
		(fp_line
			(start 0.7874 -0.4064)
			(end -0.7874 -0.4064)
			(stroke
				(width 0.1524)
				(type default)
			)
			(layer "B.SilkS")
		)
		(fp_line
			(start -0.7874 -0.4064)
			(end -0.7874 0.4064)
			(stroke
				(width 0.1524)
				(type default)
			)
			(layer "B.SilkS")
		)
		(fp_line
			(start 0.7874 0.4064)
			(end 0.7874 -0.4064)
			(stroke
				(width 0.1524)
				(type default)
			)
			(layer "B.SilkS")
		)
		(fp_line
			(start -0.7874 0.4064)
			(end 0.7874 0.4064)
			(stroke
				(width 0.1524)
				(type default)
			)
			(layer "B.SilkS")
		)
		(fp_line
			(start 0.67945 -0.305054)
			(end 0.12065 -0.305054)
			(stroke
				(width 0.1)
				(type default)
			)
			(layer "B.Fab")
		)
		(fp_line
			(start 0.12065 -0.305054)
			(end 0.12065 -0.2794)
			(stroke
				(width 0.1)
				(type default)
			)
			(layer "B.Fab")
		)
		(fp_line
			(start -0.12065 -0.3048)
			(end -0.67945 -0.3048)
			(stroke
				(width 0.1)
				(type default)
			)
			(layer "B.Fab")
		)
		(fp_line
			(start -0.67945 -0.3048)
			(end -0.67945 0.3048)
			(stroke
				(width 0.1)
				(type default)
			)
			(layer "B.Fab")
		)
		(fp_line
			(start 0.12065 -0.2794)
			(end -0.12065 -0.2794)
			(stroke
				(width 0.1)
				(type default)
			)
			(layer "B.Fab")
		)
		(fp_line
			(start -0.12065 -0.2794)
			(end -0.12065 -0.3048)
			(stroke
				(width 0.1)
				(type default)
			)
			(layer "B.Fab")
		)
		(fp_line
			(start 0.12065 0.2794)
			(end 0.12065 0.3048)
			(stroke
				(width 0.1)
				(type default)
			)
			(layer "B.Fab")
		)
		(fp_line
			(start -0.120396 0.2794)
			(end 0.12065 0.2794)
			(stroke
				(width 0.1)
				(type default)
			)
			(layer "B.Fab")
		)
		(fp_line
			(start 0.67945 0.3048)
			(end 0.67945 -0.305054)
			(stroke
				(width 0.1)
				(type default)
			)
			(layer "B.Fab")
		)
		(fp_line
			(start 0.12065 0.3048)
			(end 0.67945 0.3048)
			(stroke
				(width 0.1)
				(type default)
			)
			(layer "B.Fab")
		)
		(fp_line
			(start -0.120396 0.3048)
			(end -0.120396 0.2794)
			(stroke
				(width 0.1)
				(type default)
			)
			(layer "B.Fab")
		)
		(fp_line
			(start -0.67945 0.3048)
			(end -0.120396 0.3048)
			(stroke
				(width 0.1)
				(type default)
			)
			(layer "B.Fab")
		)
		(pad "1" smd circle
			(at 0.40005 0 270)
			(size 0 0)
			(layers "B.Cu" "B.Mask" "B.Paste")
			(net "P0V9_CPU1_RT3_2A")
		)
		(pad "2" smd circle
			(at -0.40005 0 270)
			(size 0 0)
			(layers "B.Cu" "B.Mask" "B.Paste")
			(net "GND")
		)
	)
)
